(kicad_pcb
	(version 20260206)
	(generator "pcbnew")
	(generator_version "10.0")
	(general
		(thickness 1.6)
		(legacy_teardrops no)
	)
	(paper "A4")
	(title_block
		(title "03242023_DA0F0TMBIJ0_F0T_Motherboard_J_brd_V01_OCP.brd")
		(comment 1 "Grand Teton / footprints 4571-4576 of 6105")
	)
	(layers
		(0 "F.Cu" signal "TOP")
		(4 "In1.Cu" signal "GND")
		(6 "In2.Cu" signal "IN1")
		(8 "In3.Cu" signal "GND1")
		(10 "In4.Cu" signal "IN2")
		(12 "In5.Cu" signal "GND2")
		(14 "In6.Cu" signal "IN3")
		(16 "In7.Cu" signal "GND3")
		(18 "In8.Cu" signal "VCC")
		(20 "In9.Cu" signal "VCC1")
		(22 "In10.Cu" signal "GND4")
		(24 "In11.Cu" signal "IN4")
		(26 "In12.Cu" signal "GND5")
		(28 "In13.Cu" signal "IN5")
		(30 "In14.Cu" signal "GND6")
		(32 "In15.Cu" signal "IN6")
		(34 "In16.Cu" signal "GND7")
		(2 "B.Cu" signal "BOTTOM")
		(9 "F.Adhes" user "F.Adhesive")
		(11 "B.Adhes" user "B.Adhesive")
		(13 "F.Paste" user "Package Geometry/Pastemask Top")
		(15 "B.Paste" user "Package Geometry/Pastemask Bottom")
		(5 "F.SilkS" user "Ref Des/Silkscreen Top")
		(7 "B.SilkS" user "Ref Des/Silkscreen Bottom")
		(1 "F.Mask" user "Board Geometry/Soldermask Top")
		(3 "B.Mask" user "Board Geometry/Soldermask Bottom")
		(17 "Dwgs.User" user "User.Drawings")
		(19 "Cmts.User" user "User.Comments")
		(21 "Eco1.User" user "User.Eco1")
		(23 "Eco2.User" user "User.Eco2")
		(25 "Edge.Cuts" user "Board Geometry/Outline")
		(27 "Margin" user)
		(31 "F.CrtYd" user "Package Geometry/Place Bound Top")
		(29 "B.CrtYd" user "Package Geometry/Place Bound Bottom")
		(35 "F.Fab" user "Ref Des/Assembly Top")
		(33 "B.Fab" user "Ref Des/Assembly Bottom")
	)
	(footprint ""
		(layer "B.Cu")
		(at 206.176372 -72.214994 180)
		(property "Reference" "R3215"
			(at 0 0 0)
			(layer "B.SilkS")
			(hide yes)
			(effects
				(font
					(size 1.27 1.27)
				)
				(justify mirror)
			)
		)
		(property "Value" ""
			(at 0 0 0)
			(layer "B.Fab")
			(effects
				(font
					(size 1.27 1.27)
				)
				(justify mirror)
			)
		)
		(duplicate_pad_numbers_are_jumpers no)
		(fp_line
			(start 0.7874 0.4064)
			(end 0.7874 -0.4064)
			(stroke
				(width 0.1524)
				(type default)
			)
			(layer "B.SilkS")
		)
		(fp_line
			(start 0.7874 -0.4064)
			(end -0.7874 -0.4064)
			(stroke
				(width 0.1524)
				(type default)
			)
			(layer "B.SilkS")
		)
		(fp_line
			(start -0.7874 0.4064)
			(end 0.7874 0.4064)
			(stroke
				(width 0.1524)
				(type default)
			)
			(layer "B.SilkS")
		)
		(fp_line
			(start -0.7874 -0.4064)
			(end -0.7874 0.4064)
			(stroke
				(width 0.1524)
				(type default)
			)
			(layer "B.SilkS")
		)
		(fp_line
			(start 0.67945 0.3048)
			(end 0.67945 -0.305054)
			(stroke
				(width 0.1)
				(type default)
			)
			(layer "B.Fab")
		)
		(fp_line
			(start 0.67945 -0.305054)
			(end 0.12065 -0.305054)
			(stroke
				(width 0.1)
				(type default)
			)
			(layer "B.Fab")
		)
		(fp_line
			(start 0.12065 0.3048)
			(end 0.67945 0.3048)
			(stroke
				(width 0.1)
				(type default)
			)
			(layer "B.Fab")
		)
		(fp_line
			(start 0.12065 0.2794)
			(end 0.12065 0.3048)
			(stroke
				(width 0.1)
				(type default)
			)
			(layer "B.Fab")
		)
		(fp_line
			(start 0.12065 -0.2794)
			(end -0.12065 -0.2794)
			(stroke
				(width 0.1)
				(type default)
			)
			(layer "B.Fab")
		)
		(fp_line
			(start 0.12065 -0.305054)
			(end 0.12065 -0.2794)
			(stroke
				(width 0.1)
				(type default)
			)
			(layer "B.Fab")
		)
		(fp_line
			(start -0.120396 0.3048)
			(end -0.120396 0.2794)
			(stroke
				(width 0.1)
				(type default)
			)
			(layer "B.Fab")
		)
		(fp_line
			(start -0.120396 0.2794)
			(end 0.12065 0.2794)
			(stroke
				(width 0.1)
				(type default)
			)
			(layer "B.Fab")
		)
		(fp_line
			(start -0.12065 -0.2794)
			(end -0.12065 -0.3048)
			(stroke
				(width 0.1)
				(type default)
			)
			(layer "B.Fab")
		)
		(fp_line
			(start -0.12065 -0.3048)
			(end -0.67945 -0.3048)
			(stroke
				(width 0.1)
				(type default)
			)
			(layer "B.Fab")
		)
		(fp_line
			(start -0.67945 0.3048)
			(end -0.120396 0.3048)
			(stroke
				(width 0.1)
				(type default)
			)
			(layer "B.Fab")
		)
		(fp_line
			(start -0.67945 -0.3048)
			(end -0.67945 0.3048)
			(stroke
				(width 0.1)
				(type default)
			)
			(layer "B.Fab")
		)
		(pad "1" smd circle
			(at 0.40005 0)
			(size 0 0)
			(layers "B.Cu" "B.Mask" "B.Paste")
			(net "NCSI_BMC_TXD1_R1")
		)
		(pad "2" smd circle
			(at -0.40005 0)
			(size 0 0)
			(layers "B.Cu" "B.Mask" "B.Paste")
			(net "RMII_BMC_OCP_TXD_1")
		)
	)
	(footprint ""
		(layer "B.Cu")
		(at 36.791392 -176.52238 180)
		(property "Reference" "C1366"
			(at 0 0 0)
			(layer "B.SilkS")
			(hide yes)
			(effects
				(font
					(size 1.27 1.27)
				)
				(justify mirror)
			)
		)
		(property "Value" ""
			(at 0 0 0)
			(layer "B.Fab")
			(effects
				(font
					(size 1.27 1.27)
				)
				(justify mirror)
			)
		)
		(duplicate_pad_numbers_are_jumpers no)
		(fp_line
			(start 0.7874 0.4064)
			(end 0.7874 -0.4064)
			(stroke
				(width 0.1524)
				(type default)
			)
			(layer "B.SilkS")
		)
		(fp_line
			(start 0.7874 -0.4064)
			(end -0.7874 -0.4064)
			(stroke
				(width 0.1524)
				(type default)
			)
			(layer "B.SilkS")
		)
		(fp_line
			(start -0.7874 0.4064)
			(end 0.7874 0.4064)
			(stroke
				(width 0.1524)
				(type default)
			)
			(layer "B.SilkS")
		)
		(fp_line
			(start -0.7874 -0.4064)
			(end -0.7874 0.4064)
			(stroke
				(width 0.1524)
				(type default)
			)
			(layer "B.SilkS")
		)
		(fp_line
			(start 0.67945 0.3048)
			(end 0.67945 -0.305054)
			(stroke
				(width 0.1)
				(type default)
			)
			(layer "B.Fab")
		)
		(fp_line
			(start 0.67945 -0.305054)
			(end 0.12065 -0.305054)
			(stroke
				(width 0.1)
				(type default)
			)
			(layer "B.Fab")
		)
		(fp_line
			(start 0.12065 0.3048)
			(end 0.67945 0.3048)
			(stroke
				(width 0.1)
				(type default)
			)
			(layer "B.Fab")
		)
		(fp_line
			(start 0.12065 0.2794)
			(end 0.12065 0.3048)
			(stroke
				(width 0.1)
				(type default)
			)
			(layer "B.Fab")
		)
		(fp_line
			(start 0.12065 -0.2794)
			(end -0.12065 -0.2794)
			(stroke
				(width 0.1)
				(type default)
			)
			(layer "B.Fab")
		)
		(fp_line
			(start 0.12065 -0.305054)
			(end 0.12065 -0.2794)
			(stroke
				(width 0.1)
				(type default)
			)
			(layer "B.Fab")
		)
		(fp_line
			(start -0.120396 0.3048)
			(end -0.120396 0.2794)
			(stroke
				(width 0.1)
				(type default)
			)
			(layer "B.Fab")
		)
		(fp_line
			(start -0.120396 0.2794)
			(end 0.12065 0.2794)
			(stroke
				(width 0.1)
				(type default)
			)
			(layer "B.Fab")
		)
		(fp_line
			(start -0.12065 -0.2794)
			(end -0.12065 -0.3048)
			(stroke
				(width 0.1)
				(type default)
			)
			(layer "B.Fab")
		)
		(fp_line
			(start -0.12065 -0.3048)
			(end -0.67945 -0.3048)
			(stroke
				(width 0.1)
				(type default)
			)
			(layer "B.Fab")
		)
		(fp_line
			(start -0.67945 0.3048)
			(end -0.120396 0.3048)
			(stroke
				(width 0.1)
				(type default)
			)
			(layer "B.Fab")
		)
		(fp_line
			(start -0.67945 -0.3048)
			(end -0.67945 0.3048)
			(stroke
				(width 0.1)
				(type default)
			)
			(layer "B.Fab")
		)
		(pad "1" smd circle
			(at 0.40005 0)
			(size 0 0)
			(layers "B.Cu" "B.Mask" "B.Paste")
			(net "PVNN_MAIN_CPU1")
		)
		(pad "2" smd circle
			(at -0.40005 0)
			(size 0 0)
			(layers "B.Cu" "B.Mask" "B.Paste")
			(net "GND")
		)
	)
	(footprint ""
		(layer "B.Cu")
		(at 245.835424 -101.127052 180)
		(property "Reference" "R2481"
			(at 0 0 0)
			(layer "B.SilkS")
			(hide yes)
			(effects
				(font
					(size 1.27 1.27)
				)
				(justify mirror)
			)
		)
		(property "Value" ""
			(at 0 0 0)
			(layer "B.Fab")
			(effects
				(font
					(size 1.27 1.27)
				)
				(justify mirror)
			)
		)
		(duplicate_pad_numbers_are_jumpers no)
		(fp_line
			(start 0.7874 0.4064)
			(end 0.7874 -0.4064)
			(stroke
				(width 0.1524)
				(type default)
			)
			(layer "B.SilkS")
		)
		(fp_line
			(start 0.7874 -0.4064)
			(end -0.7874 -0.4064)
			(stroke
				(width 0.1524)
				(type default)
			)
			(layer "B.SilkS")
		)
		(fp_line
			(start -0.7874 0.4064)
			(end 0.7874 0.4064)
			(stroke
				(width 0.1524)
				(type default)
			)
			(layer "B.SilkS")
		)
		(fp_line
			(start -0.7874 -0.4064)
			(end -0.7874 0.4064)
			(stroke
				(width 0.1524)
				(type default)
			)
			(layer "B.SilkS")
		)
		(fp_line
			(start 0.67945 0.3048)
			(end 0.67945 -0.305054)
			(stroke
				(width 0.1)
				(type default)
			)
			(layer "B.Fab")
		)
		(fp_line
			(start 0.67945 -0.305054)
			(end 0.12065 -0.305054)
			(stroke
				(width 0.1)
				(type default)
			)
			(layer "B.Fab")
		)
		(fp_line
			(start 0.12065 0.3048)
			(end 0.67945 0.3048)
			(stroke
				(width 0.1)
				(type default)
			)
			(layer "B.Fab")
		)
		(fp_line
			(start 0.12065 0.2794)
			(end 0.12065 0.3048)
			(stroke
				(width 0.1)
				(type default)
			)
			(layer "B.Fab")
		)
		(fp_line
			(start 0.12065 -0.2794)
			(end -0.12065 -0.2794)
			(stroke
				(width 0.1)
				(type default)
			)
			(layer "B.Fab")
		)
		(fp_line
			(start 0.12065 -0.305054)
			(end 0.12065 -0.2794)
			(stroke
				(width 0.1)
				(type default)
			)
			(layer "B.Fab")
		)
		(fp_line
			(start -0.120396 0.3048)
			(end -0.120396 0.2794)
			(stroke
				(width 0.1)
				(type default)
			)
			(layer "B.Fab")
		)
		(fp_line
			(start -0.120396 0.2794)
			(end 0.12065 0.2794)
			(stroke
				(width 0.1)
				(type default)
			)
			(layer "B.Fab")
		)
		(fp_line
			(start -0.12065 -0.2794)
			(end -0.12065 -0.3048)
			(stroke
				(width 0.1)
				(type default)
			)
			(layer "B.Fab")
		)
		(fp_line
			(start -0.12065 -0.3048)
			(end -0.67945 -0.3048)
			(stroke
				(width 0.1)
				(type default)
			)
			(layer "B.Fab")
		)
		(fp_line
			(start -0.67945 0.3048)
			(end -0.120396 0.3048)
			(stroke
				(width 0.1)
				(type default)
			)
			(layer "B.Fab")
		)
		(fp_line
			(start -0.67945 -0.3048)
			(end -0.67945 0.3048)
			(stroke
				(width 0.1)
				(type default)
			)
			(layer "B.Fab")
		)
		(pad "1" smd circle
			(at 0.40005 0)
			(size 0 0)
			(layers "B.Cu" "B.Mask" "B.Paste")
			(net "P3V3_AUX")
		)
		(pad "2" smd circle
			(at -0.40005 0)
			(size 0 0)
			(layers "B.Cu" "B.Mask" "B.Paste")
			(net "CLK_CK440_SMB_ADDR1")
		)
	)
	(footprint ""
		(layer "B.Cu")
		(at 244.944138 -128.343914 90)
		(property "Reference" "R567"
			(at 0 0 90)
			(layer "B.SilkS")
			(hide yes)
			(effects
				(font
					(size 1.27 1.27)
				)
				(justify mirror)
			)
		)
		(property "Value" ""
			(at 0 0 90)
			(layer "B.Fab")
			(effects
				(font
					(size 1.27 1.27)
				)
				(justify mirror)
			)
		)
		(duplicate_pad_numbers_are_jumpers no)
		(fp_line
			(start 0.7874 -0.4064)
			(end -0.7874 -0.4064)
			(stroke
				(width 0.1524)
				(type default)
			)
			(layer "B.SilkS")
		)
		(fp_line
			(start -0.7874 -0.4064)
			(end -0.7874 0.4064)
			(stroke
				(width 0.1524)
				(type default)
			)
			(layer "B.SilkS")
		)
		(fp_line
			(start 0.7874 0.4064)
			(end 0.7874 -0.4064)
			(stroke
				(width 0.1524)
				(type default)
			)
			(layer "B.SilkS")
		)
		(fp_line
			(start -0.7874 0.4064)
			(end 0.7874 0.4064)
			(stroke
				(width 0.1524)
				(type default)
			)
			(layer "B.SilkS")
		)
		(fp_line
			(start 0.67945 -0.305054)
			(end 0.12065 -0.305054)
			(stroke
				(width 0.1)
				(type default)
			)
			(layer "B.Fab")
		)
		(fp_line
			(start 0.12065 -0.305054)
			(end 0.12065 -0.2794)
			(stroke
				(width 0.1)
				(type default)
			)
			(layer "B.Fab")
		)
		(fp_line
			(start -0.12065 -0.3048)
			(end -0.67945 -0.3048)
			(stroke
				(width 0.1)
				(type default)
			)
			(layer "B.Fab")
		)
		(fp_line
			(start -0.67945 -0.3048)
			(end -0.67945 0.3048)
			(stroke
				(width 0.1)
				(type default)
			)
			(layer "B.Fab")
		)
		(fp_line
			(start 0.12065 -0.2794)
			(end -0.12065 -0.2794)
			(stroke
				(width 0.1)
				(type default)
			)
			(layer "B.Fab")
		)
		(fp_line
			(start -0.12065 -0.2794)
			(end -0.12065 -0.3048)
			(stroke
				(width 0.1)
				(type default)
			)
			(layer "B.Fab")
		)
		(fp_line
			(start 0.12065 0.2794)
			(end 0.12065 0.3048)
			(stroke
				(width 0.1)
				(type default)
			)
			(layer "B.Fab")
		)
		(fp_line
			(start -0.120396 0.2794)
			(end 0.12065 0.2794)
			(stroke
				(width 0.1)
				(type default)
			)
			(layer "B.Fab")
		)
		(fp_line
			(start 0.67945 0.3048)
			(end 0.67945 -0.305054)
			(stroke
				(width 0.1)
				(type default)
			)
			(layer "B.Fab")
		)
		(fp_line
			(start 0.12065 0.3048)
			(end 0.67945 0.3048)
			(stroke
				(width 0.1)
				(type default)
			)
			(layer "B.Fab")
		)
		(fp_line
			(start -0.120396 0.3048)
			(end -0.120396 0.2794)
			(stroke
				(width 0.1)
				(type default)
			)
			(layer "B.Fab")
		)
		(fp_line
			(start -0.67945 0.3048)
			(end -0.120396 0.3048)
			(stroke
				(width 0.1)
				(type default)
			)
			(layer "B.Fab")
		)
		(pad "1" smd circle
			(at 0.40005 0 270)
			(size 0 0)
			(layers "B.Cu" "B.Mask" "B.Paste")
			(net "P3V3")
		)
		(pad "2" smd circle
			(at -0.40005 0 270)
			(size 0 0)
			(layers "B.Cu" "B.Mask" "B.Paste")
			(net "PD_DB2000_SMB_SA1")
		)
	)
	(footprint ""
		(layer "B.Cu")
		(at 452.62546 -10.60577 90)
		(property "Reference" "R420"
			(at 0 0 90)
			(layer "B.SilkS")
			(hide yes)
			(effects
				(font
					(size 1.27 1.27)
				)
				(justify mirror)
			)
		)
		(property "Value" ""
			(at 0 0 90)
			(layer "B.Fab")
			(effects
				(font
					(size 1.27 1.27)
				)
				(justify mirror)
			)
		)
		(duplicate_pad_numbers_are_jumpers no)
		(fp_line
			(start 0.7874 -0.4064)
			(end -0.7874 -0.4064)
			(stroke
				(width 0.1524)
				(type default)
			)
			(layer "B.SilkS")
		)
		(fp_line
			(start -0.7874 -0.4064)
			(end -0.7874 0.4064)
			(stroke
				(width 0.1524)
				(type default)
			)
			(layer "B.SilkS")
		)
		(fp_line
			(start 0.7874 0.4064)
			(end 0.7874 -0.4064)
			(stroke
				(width 0.1524)
				(type default)
			)
			(layer "B.SilkS")
		)
		(fp_line
			(start -0.7874 0.4064)
			(end 0.7874 0.4064)
			(stroke
				(width 0.1524)
				(type default)
			)
			(layer "B.SilkS")
		)
		(fp_line
			(start 0.67945 -0.305054)
			(end 0.12065 -0.305054)
			(stroke
				(width 0.1)
				(type default)
			)
			(layer "B.Fab")
		)
		(fp_line
			(start 0.12065 -0.305054)
			(end 0.12065 -0.2794)
			(stroke
				(width 0.1)
				(type default)
			)
			(layer "B.Fab")
		)
		(fp_line
			(start -0.12065 -0.3048)
			(end -0.67945 -0.3048)
			(stroke
				(width 0.1)
				(type default)
			)
			(layer "B.Fab")
		)
		(fp_line
			(start -0.67945 -0.3048)
			(end -0.67945 0.3048)
			(stroke
				(width 0.1)
				(type default)
			)
			(layer "B.Fab")
		)
		(fp_line
			(start 0.12065 -0.2794)
			(end -0.12065 -0.2794)
			(stroke
				(width 0.1)
				(type default)
			)
			(layer "B.Fab")
		)
		(fp_line
			(start -0.12065 -0.2794)
			(end -0.12065 -0.3048)
			(stroke
				(width 0.1)
				(type default)
			)
			(layer "B.Fab")
		)
		(fp_line
			(start 0.12065 0.2794)
			(end 0.12065 0.3048)
			(stroke
				(width 0.1)
				(type default)
			)
			(layer "B.Fab")
		)
		(fp_line
			(start -0.120396 0.2794)
			(end 0.12065 0.2794)
			(stroke
				(width 0.1)
				(type default)
			)
			(layer "B.Fab")
		)
		(fp_line
			(start 0.67945 0.3048)
			(end 0.67945 -0.305054)
			(stroke
				(width 0.1)
				(type default)
			)
			(layer "B.Fab")
		)
		(fp_line
			(start 0.12065 0.3048)
			(end 0.67945 0.3048)
			(stroke
				(width 0.1)
				(type default)
			)
			(layer "B.Fab")
		)
		(fp_line
			(start -0.120396 0.3048)
			(end -0.120396 0.2794)
			(stroke
				(width 0.1)
				(type default)
			)
			(layer "B.Fab")
		)
		(fp_line
			(start -0.67945 0.3048)
			(end -0.120396 0.3048)
			(stroke
				(width 0.1)
				(type default)
			)
			(layer "B.Fab")
		)
		(pad "1" smd circle
			(at 0.40005 0 270)
			(size 0 0)
			(layers "B.Cu" "B.Mask" "B.Paste")
			(net "SGPIO_OCP_SFF_LD_N")
		)
		(pad "2" smd circle
			(at -0.40005 0 270)
			(size 0 0)
			(layers "B.Cu" "B.Mask" "B.Paste")
			(net "P3V3_OCP_SFF")
		)
	)
	(footprint ""
		(layer "B.Cu")
		(at 441.005214 -321.549776 -90)
		(property "Reference" "C43"
			(at 0 0 90)
			(layer "B.SilkS")
			(hide yes)
			(effects
				(font
					(size 1.27 1.27)
				)
				(justify mirror)
			)
		)
		(property "Value" ""
			(at 0 0 90)
			(layer "B.Fab")
			(effects
				(font
					(size 1.27 1.27)
				)
				(justify mirror)
			)
		)
		(duplicate_pad_numbers_are_jumpers no)
		(fp_line
			(start -1.524 0.762)
			(end 1.524 0.762)
			(stroke
				(width 0.1524)
				(type default)
			)
			(layer "B.SilkS")
		)
		(fp_line
			(start 1.524 0.762)
			(end 1.524 -0.762)
			(stroke
				(width 0.1524)
				(type default)
			)
			(layer "B.SilkS")
		)
		(fp_line
			(start -1.524 -0.762)
			(end -1.524 0.762)
			(stroke
				(width 0.1524)
				(type default)
			)
			(layer "B.SilkS")
		)
		(fp_line
			(start 1.524 -0.762)
			(end -1.524 -0.762)
			(stroke
				(width 0.1524)
				(type default)
			)
			(layer "B.SilkS")
		)
		(fp_line
			(start -1.1049 0.724916)
			(end -1.1049 -0.724916)
			(stroke
				(width 0.1)
				(type default)
			)
			(layer "B.Fab")
		)
		(fp_line
			(start 1.1049 0.724916)
			(end -1.1049 0.724916)
			(stroke
				(width 0.1)
				(type default)
			)
			(layer "B.Fab")
		)
		(fp_line
			(start -1.1049 -0.724916)
			(end 1.1049 -0.724916)
			(stroke
				(width 0.1)
				(type default)
			)
			(layer "B.Fab")
		)
		(fp_line
			(start 1.1049 -0.724916)
			(end 1.1049 0.724916)
			(stroke
				(width 0.1)
				(type default)
			)
			(layer "B.Fab")
		)
		(pad "1" smd rect
			(at 0.889 0 270)
			(size 1.016 1.27)
			(layers "B.Cu" "B.Mask" "B.Paste")
			(net "P12V_S3_AUX_CPU0_NVDIMM")
		)
		(pad "2" smd rect
			(at -0.889 0 270)
			(size 1.016 1.27)
			(layers "B.Cu" "B.Mask" "B.Paste")
			(net "GND")
		)
	)
)
